(kicad_pcb
	(version 20260206)
	(generator "pcbnew")
	(generator_version "10.0")
	(general
		(thickness 1.6)
		(legacy_teardrops no)
	)
	(paper "A4")
	(title_block
		(title "04192023_DAF0TMB3IC0_F0TG_MB_C_brd_V02_OCP.brd")
		(comment 1 "Grand Teton / footprints 2343-2348 of 8354")
	)
	(layers
		(0 "F.Cu" signal "TOP")
		(4 "In1.Cu" signal "GND")
		(6 "In2.Cu" signal "IN1")
		(8 "In3.Cu" signal "GND1")
		(10 "In4.Cu" signal "IN2")
		(12 "In5.Cu" signal "GND2")
		(14 "In6.Cu" signal "IN3")
		(16 "In7.Cu" signal "GND3")
		(18 "In8.Cu" signal "VCC")
		(20 "In9.Cu" signal "VCC1")
		(22 "In10.Cu" signal "GND4")
		(24 "In11.Cu" signal "IN4")
		(26 "In12.Cu" signal "GND5")
		(28 "In13.Cu" signal "IN5")
		(30 "In14.Cu" signal "GND6")
		(32 "In15.Cu" signal "IN6")
		(34 "In16.Cu" signal "GND7")
		(2 "B.Cu" signal "BOTTOM")
		(9 "F.Adhes" user "F.Adhesive")
		(11 "B.Adhes" user "B.Adhesive")
		(13 "F.Paste" user "Package Geometry/Pastemask Top")
		(15 "B.Paste" user "Package Geometry/Pastemask Bottom")
		(5 "F.SilkS" user "Ref Des/Silkscreen Top")
		(7 "B.SilkS" user "Ref Des/Silkscreen Bottom")
		(1 "F.Mask" user "Board Geometry/Soldermask Top")
		(3 "B.Mask" user "Board Geometry/Soldermask Bottom")
		(17 "Dwgs.User" user "User.Drawings")
		(19 "Cmts.User" user "User.Comments")
		(21 "Eco1.User" user "User.Eco1")
		(23 "Eco2.User" user "User.Eco2")
		(25 "Edge.Cuts" user "Board Geometry/Outline")
		(27 "Margin" user)
		(31 "F.CrtYd" user "Package Geometry/Place Bound Top")
		(29 "B.CrtYd" user "Package Geometry/Place Bound Bottom")
		(35 "F.Fab" user "Ref Des/Assembly Top")
		(33 "B.Fab" user "Ref Des/Assembly Bottom")
	)
	(footprint ""
		(layer "F.Cu")
		(at 130.048 -109.474 90)
		(property "Reference" "R8114"
			(at 0 0 90)
			(layer "F.SilkS")
			(hide yes)
			(effects
				(font
					(size 1.27 1.27)
				)
			)
		)
		(property "Value" ""
			(at 0 0 90)
			(layer "F.Fab")
			(effects
				(font
					(size 1.27 1.27)
				)
			)
		)
		(duplicate_pad_numbers_are_jumpers no)
		(fp_line
			(start 0.7874 -0.4064)
			(end 0.7874 0.4064)
			(stroke
				(width 0.1524)
				(type default)
			)
			(layer "F.SilkS")
		)
		(fp_line
			(start -0.7874 -0.4064)
			(end 0.7874 -0.4064)
			(stroke
				(width 0.1524)
				(type default)
			)
			(layer "F.SilkS")
		)
		(fp_line
			(start 0.7874 0.4064)
			(end -0.7874 0.4064)
			(stroke
				(width 0.1524)
				(type default)
			)
			(layer "F.SilkS")
		)
		(fp_line
			(start -0.7874 0.4064)
			(end -0.7874 -0.4064)
			(stroke
				(width 0.1524)
				(type default)
			)
			(layer "F.SilkS")
		)
		(fp_line
			(start -0.12065 -0.305054)
			(end -0.12065 -0.2794)
			(stroke
				(width 0.1)
				(type default)
			)
			(layer "F.Fab")
		)
		(fp_line
			(start -0.67945 -0.305054)
			(end -0.12065 -0.305054)
			(stroke
				(width 0.1)
				(type default)
			)
			(layer "F.Fab")
		)
		(fp_line
			(start 0.67945 -0.3048)
			(end 0.67945 0.3048)
			(stroke
				(width 0.1)
				(type default)
			)
			(layer "F.Fab")
		)
		(fp_line
			(start 0.12065 -0.3048)
			(end 0.67945 -0.3048)
			(stroke
				(width 0.1)
				(type default)
			)
			(layer "F.Fab")
		)
		(fp_line
			(start 0.12065 -0.2794)
			(end 0.12065 -0.3048)
			(stroke
				(width 0.1)
				(type default)
			)
			(layer "F.Fab")
		)
		(fp_line
			(start -0.12065 -0.2794)
			(end 0.12065 -0.2794)
			(stroke
				(width 0.1)
				(type default)
			)
			(layer "F.Fab")
		)
		(fp_line
			(start 0.120396 0.2794)
			(end -0.12065 0.2794)
			(stroke
				(width 0.1)
				(type default)
			)
			(layer "F.Fab")
		)
		(fp_line
			(start -0.12065 0.2794)
			(end -0.12065 0.3048)
			(stroke
				(width 0.1)
				(type default)
			)
			(layer "F.Fab")
		)
		(fp_line
			(start 0.67945 0.3048)
			(end 0.120396 0.3048)
			(stroke
				(width 0.1)
				(type default)
			)
			(layer "F.Fab")
		)
		(fp_line
			(start 0.120396 0.3048)
			(end 0.120396 0.2794)
			(stroke
				(width 0.1)
				(type default)
			)
			(layer "F.Fab")
		)
		(fp_line
			(start -0.12065 0.3048)
			(end -0.67945 0.3048)
			(stroke
				(width 0.1)
				(type default)
			)
			(layer "F.Fab")
		)
		(fp_line
			(start -0.67945 0.3048)
			(end -0.67945 -0.305054)
			(stroke
				(width 0.1)
				(type default)
			)
			(layer "F.Fab")
		)
		(pad "1" smd circle
			(at -0.40005 0 90)
			(size 0 0)
			(layers "F.Cu" "F.Mask" "F.Paste")
			(net "P12V_AUX")
		)
		(pad "2" smd circle
			(at 0.40005 0 90)
			(size 0 0)
			(layers "F.Cu" "F.Mask" "F.Paste")
			(net "P12V_AUX_UV_ADR_TRIGGER")
		)
	)
	(footprint ""
		(layer "F.Cu")
		(at 184.785 -100.294948 -90)
		(property "Reference" "R1188"
			(at 0 0 270)
			(layer "F.SilkS")
			(hide yes)
			(effects
				(font
					(size 1.27 1.27)
				)
			)
		)
		(property "Value" ""
			(at 0 0 270)
			(layer "F.Fab")
			(effects
				(font
					(size 1.27 1.27)
				)
			)
		)
		(duplicate_pad_numbers_are_jumpers no)
		(fp_line
			(start -0.7874 0.4064)
			(end -0.7874 -0.4064)
			(stroke
				(width 0.1524)
				(type default)
			)
			(layer "F.SilkS")
		)
		(fp_line
			(start 0.7874 0.4064)
			(end -0.7874 0.4064)
			(stroke
				(width 0.1524)
				(type default)
			)
			(layer "F.SilkS")
		)
		(fp_line
			(start -0.7874 -0.4064)
			(end 0.7874 -0.4064)
			(stroke
				(width 0.1524)
				(type default)
			)
			(layer "F.SilkS")
		)
		(fp_line
			(start 0.7874 -0.4064)
			(end 0.7874 0.4064)
			(stroke
				(width 0.1524)
				(type default)
			)
			(layer "F.SilkS")
		)
		(fp_line
			(start -0.67945 0.3048)
			(end -0.67945 -0.305054)
			(stroke
				(width 0.1)
				(type default)
			)
			(layer "F.Fab")
		)
		(fp_line
			(start -0.12065 0.3048)
			(end -0.67945 0.3048)
			(stroke
				(width 0.1)
				(type default)
			)
			(layer "F.Fab")
		)
		(fp_line
			(start 0.120396 0.3048)
			(end 0.120396 0.2794)
			(stroke
				(width 0.1)
				(type default)
			)
			(layer "F.Fab")
		)
		(fp_line
			(start 0.67945 0.3048)
			(end 0.120396 0.3048)
			(stroke
				(width 0.1)
				(type default)
			)
			(layer "F.Fab")
		)
		(fp_line
			(start -0.12065 0.2794)
			(end -0.12065 0.3048)
			(stroke
				(width 0.1)
				(type default)
			)
			(layer "F.Fab")
		)
		(fp_line
			(start 0.120396 0.2794)
			(end -0.12065 0.2794)
			(stroke
				(width 0.1)
				(type default)
			)
			(layer "F.Fab")
		)
		(fp_line
			(start -0.12065 -0.2794)
			(end 0.12065 -0.2794)
			(stroke
				(width 0.1)
				(type default)
			)
			(layer "F.Fab")
		)
		(fp_line
			(start 0.12065 -0.2794)
			(end 0.12065 -0.3048)
			(stroke
				(width 0.1)
				(type default)
			)
			(layer "F.Fab")
		)
		(fp_line
			(start 0.12065 -0.3048)
			(end 0.67945 -0.3048)
			(stroke
				(width 0.1)
				(type default)
			)
			(layer "F.Fab")
		)
		(fp_line
			(start 0.67945 -0.3048)
			(end 0.67945 0.3048)
			(stroke
				(width 0.1)
				(type default)
			)
			(layer "F.Fab")
		)
		(fp_line
			(start -0.67945 -0.305054)
			(end -0.12065 -0.305054)
			(stroke
				(width 0.1)
				(type default)
			)
			(layer "F.Fab")
		)
		(fp_line
			(start -0.12065 -0.305054)
			(end -0.12065 -0.2794)
			(stroke
				(width 0.1)
				(type default)
			)
			(layer "F.Fab")
		)
		(pad "1" smd circle
			(at -0.40005 0 270)
			(size 0 0)
			(layers "F.Cu" "F.Mask" "F.Paste")
			(net "PVDDCR_CPU1_P1_SMB_ALERT")
		)
		(pad "2" smd circle
			(at 0.40005 0 270)
			(size 0 0)
			(layers "F.Cu" "F.Mask" "F.Paste")
			(net "P3V3_AUX")
		)
	)
	(footprint ""
		(layer "F.Cu")
		(at 100.378514 -177.481484)
		(property "Reference" "PR195"
			(at 0 0 0)
			(layer "F.SilkS")
			(hide yes)
			(effects
				(font
					(size 1.27 1.27)
				)
			)
		)
		(property "Value" ""
			(at 0 0 0)
			(layer "F.Fab")
			(effects
				(font
					(size 1.27 1.27)
				)
			)
		)
		(duplicate_pad_numbers_are_jumpers no)
		(fp_line
			(start -0.7874 -0.4064)
			(end 0.7874 -0.4064)
			(stroke
				(width 0.1524)
				(type default)
			)
			(layer "F.SilkS")
		)
		(fp_line
			(start -0.7874 0.4064)
			(end -0.7874 -0.4064)
			(stroke
				(width 0.1524)
				(type default)
			)
			(layer "F.SilkS")
		)
		(fp_line
			(start 0.7874 -0.4064)
			(end 0.7874 0.4064)
			(stroke
				(width 0.1524)
				(type default)
			)
			(layer "F.SilkS")
		)
		(fp_line
			(start 0.7874 0.4064)
			(end -0.7874 0.4064)
			(stroke
				(width 0.1524)
				(type default)
			)
			(layer "F.SilkS")
		)
		(fp_line
			(start -0.67945 -0.305054)
			(end -0.12065 -0.305054)
			(stroke
				(width 0.1)
				(type default)
			)
			(layer "F.Fab")
		)
		(fp_line
			(start -0.67945 0.3048)
			(end -0.67945 -0.305054)
			(stroke
				(width 0.1)
				(type default)
			)
			(layer "F.Fab")
		)
		(fp_line
			(start -0.12065 -0.305054)
			(end -0.12065 -0.2794)
			(stroke
				(width 0.1)
				(type default)
			)
			(layer "F.Fab")
		)
		(fp_line
			(start -0.12065 -0.2794)
			(end 0.12065 -0.2794)
			(stroke
				(width 0.1)
				(type default)
			)
			(layer "F.Fab")
		)
		(fp_line
			(start -0.12065 0.2794)
			(end -0.12065 0.3048)
			(stroke
				(width 0.1)
				(type default)
			)
			(layer "F.Fab")
		)
		(fp_line
			(start -0.12065 0.3048)
			(end -0.67945 0.3048)
			(stroke
				(width 0.1)
				(type default)
			)
			(layer "F.Fab")
		)
		(fp_line
			(start 0.120396 0.2794)
			(end -0.12065 0.2794)
			(stroke
				(width 0.1)
				(type default)
			)
			(layer "F.Fab")
		)
		(fp_line
			(start 0.120396 0.3048)
			(end 0.120396 0.2794)
			(stroke
				(width 0.1)
				(type default)
			)
			(layer "F.Fab")
		)
		(fp_line
			(start 0.12065 -0.3048)
			(end 0.67945 -0.3048)
			(stroke
				(width 0.1)
				(type default)
			)
			(layer "F.Fab")
		)
		(fp_line
			(start 0.12065 -0.2794)
			(end 0.12065 -0.3048)
			(stroke
				(width 0.1)
				(type default)
			)
			(layer "F.Fab")
		)
		(fp_line
			(start 0.67945 -0.3048)
			(end 0.67945 0.3048)
			(stroke
				(width 0.1)
				(type default)
			)
			(layer "F.Fab")
		)
		(fp_line
			(start 0.67945 0.3048)
			(end 0.120396 0.3048)
			(stroke
				(width 0.1)
				(type default)
			)
			(layer "F.Fab")
		)
		(pad "1" smd circle
			(at -0.40005 0)
			(size 0 0)
			(layers "F.Cu" "F.Mask" "F.Paste")
			(net "GND")
		)
		(pad "2" smd circle
			(at 0.40005 0)
			(size 0 0)
			(layers "F.Cu" "F.Mask" "F.Paste")
			(net "PVDDCR_CPU0_P1_LSET3")
		)
	)
	(footprint ""
		(layer "F.Cu")
		(at 50.616866 -437.642 180)
		(property "Reference" "R3467"
			(at 0 0 180)
			(layer "F.SilkS")
			(hide yes)
			(effects
				(font
					(size 1.27 1.27)
				)
			)
		)
		(property "Value" ""
			(at 0 0 180)
			(layer "F.Fab")
			(effects
				(font
					(size 1.27 1.27)
				)
			)
		)
		(duplicate_pad_numbers_are_jumpers no)
		(fp_line
			(start 0.7874 0.4064)
			(end -0.7874 0.4064)
			(stroke
				(width 0.1524)
				(type default)
			)
			(layer "F.SilkS")
		)
		(fp_line
			(start 0.7874 -0.4064)
			(end 0.7874 0.4064)
			(stroke
				(width 0.1524)
				(type default)
			)
			(layer "F.SilkS")
		)
		(fp_line
			(start -0.7874 0.4064)
			(end -0.7874 -0.4064)
			(stroke
				(width 0.1524)
				(type default)
			)
			(layer "F.SilkS")
		)
		(fp_line
			(start -0.7874 -0.4064)
			(end 0.7874 -0.4064)
			(stroke
				(width 0.1524)
				(type default)
			)
			(layer "F.SilkS")
		)
		(fp_line
			(start 0.67945 0.3048)
			(end 0.120396 0.3048)
			(stroke
				(width 0.1)
				(type default)
			)
			(layer "F.Fab")
		)
		(fp_line
			(start 0.67945 -0.3048)
			(end 0.67945 0.3048)
			(stroke
				(width 0.1)
				(type default)
			)
			(layer "F.Fab")
		)
		(fp_line
			(start 0.12065 -0.2794)
			(end 0.12065 -0.3048)
			(stroke
				(width 0.1)
				(type default)
			)
			(layer "F.Fab")
		)
		(fp_line
			(start 0.12065 -0.3048)
			(end 0.67945 -0.3048)
			(stroke
				(width 0.1)
				(type default)
			)
			(layer "F.Fab")
		)
		(fp_line
			(start 0.120396 0.3048)
			(end 0.120396 0.2794)
			(stroke
				(width 0.1)
				(type default)
			)
			(layer "F.Fab")
		)
		(fp_line
			(start 0.120396 0.2794)
			(end -0.12065 0.2794)
			(stroke
				(width 0.1)
				(type default)
			)
			(layer "F.Fab")
		)
		(fp_line
			(start -0.12065 0.3048)
			(end -0.67945 0.3048)
			(stroke
				(width 0.1)
				(type default)
			)
			(layer "F.Fab")
		)
		(fp_line
			(start -0.12065 0.2794)
			(end -0.12065 0.3048)
			(stroke
				(width 0.1)
				(type default)
			)
			(layer "F.Fab")
		)
		(fp_line
			(start -0.12065 -0.2794)
			(end 0.12065 -0.2794)
			(stroke
				(width 0.1)
				(type default)
			)
			(layer "F.Fab")
		)
		(fp_line
			(start -0.12065 -0.305054)
			(end -0.12065 -0.2794)
			(stroke
				(width 0.1)
				(type default)
			)
			(layer "F.Fab")
		)
		(fp_line
			(start -0.67945 0.3048)
			(end -0.67945 -0.305054)
			(stroke
				(width 0.1)
				(type default)
			)
			(layer "F.Fab")
		)
		(fp_line
			(start -0.67945 -0.305054)
			(end -0.12065 -0.305054)
			(stroke
				(width 0.1)
				(type default)
			)
			(layer "F.Fab")
		)
		(pad "1" smd circle
			(at -0.40005 0 180)
			(size 0 0)
			(layers "F.Cu" "F.Mask" "F.Paste")
			(net "RST_PERST_0_SWB_BUF_R_N")
		)
		(pad "2" smd circle
			(at 0.40005 0 180)
			(size 0 0)
			(layers "F.Cu" "F.Mask" "F.Paste")
			(net "GND")
		)
	)
	(footprint ""
		(layer "F.Cu")
		(at 35.649662 -419.249098 -90)
		(property "Reference" "R3290"
			(at 0 0 270)
			(layer "F.SilkS")
			(hide yes)
			(effects
				(font
					(size 1.27 1.27)
				)
			)
		)
		(property "Value" ""
			(at 0 0 270)
			(layer "F.Fab")
			(effects
				(font
					(size 1.27 1.27)
				)
			)
		)
		(duplicate_pad_numbers_are_jumpers no)
		(fp_line
			(start -0.7874 0.4064)
			(end -0.7874 -0.4064)
			(stroke
				(width 0.1524)
				(type default)
			)
			(layer "F.SilkS")
		)
		(fp_line
			(start 0.7874 0.4064)
			(end -0.7874 0.4064)
			(stroke
				(width 0.1524)
				(type default)
			)
			(layer "F.SilkS")
		)
		(fp_line
			(start -0.7874 -0.4064)
			(end 0.7874 -0.4064)
			(stroke
				(width 0.1524)
				(type default)
			)
			(layer "F.SilkS")
		)
		(fp_line
			(start 0.7874 -0.4064)
			(end 0.7874 0.4064)
			(stroke
				(width 0.1524)
				(type default)
			)
			(layer "F.SilkS")
		)
		(fp_line
			(start -0.67945 0.3048)
			(end -0.67945 -0.305054)
			(stroke
				(width 0.1)
				(type default)
			)
			(layer "F.Fab")
		)
		(fp_line
			(start -0.12065 0.3048)
			(end -0.67945 0.3048)
			(stroke
				(width 0.1)
				(type default)
			)
			(layer "F.Fab")
		)
		(fp_line
			(start 0.120396 0.3048)
			(end 0.120396 0.2794)
			(stroke
				(width 0.1)
				(type default)
			)
			(layer "F.Fab")
		)
		(fp_line
			(start 0.67945 0.3048)
			(end 0.120396 0.3048)
			(stroke
				(width 0.1)
				(type default)
			)
			(layer "F.Fab")
		)
		(fp_line
			(start -0.12065 0.2794)
			(end -0.12065 0.3048)
			(stroke
				(width 0.1)
				(type default)
			)
			(layer "F.Fab")
		)
		(fp_line
			(start 0.120396 0.2794)
			(end -0.12065 0.2794)
			(stroke
				(width 0.1)
				(type default)
			)
			(layer "F.Fab")
		)
		(fp_line
			(start -0.12065 -0.2794)
			(end 0.12065 -0.2794)
			(stroke
				(width 0.1)
				(type default)
			)
			(layer "F.Fab")
		)
		(fp_line
			(start 0.12065 -0.2794)
			(end 0.12065 -0.3048)
			(stroke
				(width 0.1)
				(type default)
			)
			(layer "F.Fab")
		)
		(fp_line
			(start 0.12065 -0.3048)
			(end 0.67945 -0.3048)
			(stroke
				(width 0.1)
				(type default)
			)
			(layer "F.Fab")
		)
		(fp_line
			(start 0.67945 -0.3048)
			(end 0.67945 0.3048)
			(stroke
				(width 0.1)
				(type default)
			)
			(layer "F.Fab")
		)
		(fp_line
			(start -0.67945 -0.305054)
			(end -0.12065 -0.305054)
			(stroke
				(width 0.1)
				(type default)
			)
			(layer "F.Fab")
		)
		(fp_line
			(start -0.12065 -0.305054)
			(end -0.12065 -0.2794)
			(stroke
				(width 0.1)
				(type default)
			)
			(layer "F.Fab")
		)
		(pad "1" smd circle
			(at -0.40005 0 270)
			(size 0 0)
			(layers "F.Cu" "F.Mask" "F.Paste")
			(net "FM_P2E_SWA")
		)
		(pad "2" smd circle
			(at 0.40005 0 270)
			(size 0 0)
			(layers "F.Cu" "F.Mask" "F.Paste")
			(net "GND")
		)
	)
	(footprint ""
		(layer "F.Cu")
		(at 424.217338 -365.797846 90)
		(property "Reference" "PR130"
			(at 0 0 90)
			(layer "F.SilkS")
			(hide yes)
			(effects
				(font
					(size 1.27 1.27)
				)
			)
		)
		(property "Value" ""
			(at 0 0 90)
			(layer "F.Fab")
			(effects
				(font
					(size 1.27 1.27)
				)
			)
		)
		(duplicate_pad_numbers_are_jumpers no)
		(fp_line
			(start 0.7874 -0.4064)
			(end 0.7874 0.4064)
			(stroke
				(width 0.1524)
				(type default)
			)
			(layer "F.SilkS")
		)
		(fp_line
			(start -0.7874 -0.4064)
			(end 0.7874 -0.4064)
			(stroke
				(width 0.1524)
				(type default)
			)
			(layer "F.SilkS")
		)
		(fp_line
			(start 0.7874 0.4064)
			(end -0.7874 0.4064)
			(stroke
				(width 0.1524)
				(type default)
			)
			(layer "F.SilkS")
		)
		(fp_line
			(start -0.7874 0.4064)
			(end -0.7874 -0.4064)
			(stroke
				(width 0.1524)
				(type default)
			)
			(layer "F.SilkS")
		)
		(fp_line
			(start -0.12065 -0.305054)
			(end -0.12065 -0.2794)
			(stroke
				(width 0.1)
				(type default)
			)
			(layer "F.Fab")
		)
		(fp_line
			(start -0.67945 -0.305054)
			(end -0.12065 -0.305054)
			(stroke
				(width 0.1)
				(type default)
			)
			(layer "F.Fab")
		)
		(fp_line
			(start 0.67945 -0.3048)
			(end 0.67945 0.3048)
			(stroke
				(width 0.1)
				(type default)
			)
			(layer "F.Fab")
		)
		(fp_line
			(start 0.12065 -0.3048)
			(end 0.67945 -0.3048)
			(stroke
				(width 0.1)
				(type default)
			)
			(layer "F.Fab")
		)
		(fp_line
			(start 0.12065 -0.2794)
			(end 0.12065 -0.3048)
			(stroke
				(width 0.1)
				(type default)
			)
			(layer "F.Fab")
		)
		(fp_line
			(start -0.12065 -0.2794)
			(end 0.12065 -0.2794)
			(stroke
				(width 0.1)
				(type default)
			)
			(layer "F.Fab")
		)
		(fp_line
			(start 0.120396 0.2794)
			(end -0.12065 0.2794)
			(stroke
				(width 0.1)
				(type default)
			)
			(layer "F.Fab")
		)
		(fp_line
			(start -0.12065 0.2794)
			(end -0.12065 0.3048)
			(stroke
				(width 0.1)
				(type default)
			)
			(layer "F.Fab")
		)
		(fp_line
			(start 0.67945 0.3048)
			(end 0.120396 0.3048)
			(stroke
				(width 0.1)
				(type default)
			)
			(layer "F.Fab")
		)
		(fp_line
			(start 0.120396 0.3048)
			(end 0.120396 0.2794)
			(stroke
				(width 0.1)
				(type default)
			)
			(layer "F.Fab")
		)
		(fp_line
			(start -0.12065 0.3048)
			(end -0.67945 0.3048)
			(stroke
				(width 0.1)
				(type default)
			)
			(layer "F.Fab")
		)
		(fp_line
			(start -0.67945 0.3048)
			(end -0.67945 -0.305054)
			(stroke
				(width 0.1)
				(type default)
			)
			(layer "F.Fab")
		)
		(pad "1" smd circle
			(at -0.40005 0 90)
			(size 0 0)
			(layers "F.Cu" "F.Mask" "F.Paste")
			(net "PVDD11_S3_P0_VCC")
		)
		(pad "2" smd circle
			(at 0.40005 0 90)
			(size 0 0)
			(layers "F.Cu" "F.Mask" "F.Paste")
			(net "P3V3_AUX")
		)
	)
)
